# T6G (Grand Teton) — schematic netlist excerpt (pin names and nets, part order shuffled) for the footprints in the layout excerpt that follows; sources: Cadence DE-HDL packaged netlist, KiCad conversion of 04192023_DAF0TMB3IC0_F0TG_MB_C_brd_V02_OCP.brd

U8005  LM4040AIM3X25NOPB  LM4040AIM3X-2.5/NOPB EMPTY  pkg SOT23_123_2-92X1-3  page 267
  \1+\  = OC_P2V5_COMP
  \2-\  = GND
  \3\  = NC

C440  Q_CAP  1UF 4V 20% X6S  pkg 0201  page 356 : A = P1V8_CPU1_RT3_1A ; B = GND
C2441  Q_CAP  22UF 4V 20% X6S  pkg C0402  page 74 : A = PVDDCR_SOC_P1 ; B = GND

(kicad_pcb
	(version 20260206)
	(generator "pcbnew")
	(generator_version "10.0")
	(general
		(thickness 1.6)
		(legacy_teardrops no)
	)
	(paper "A4")
	(title_block
		(title "04192023_DAF0TMB3IC0_F0TG_MB_C_brd_V02_OCP.brd")
		(comment 1 "Grand Teton / footprints 7347-7349 of 8354")
	)
	(layers
		(0 "F.Cu" signal "TOP")
		(4 "In1.Cu" signal "GND")
		(6 "In2.Cu" signal "IN1")
		(8 "In3.Cu" signal "GND1")
		(10 "In4.Cu" signal "IN2")
		(12 "In5.Cu" signal "GND2")
		(14 "In6.Cu" signal "IN3")
		(16 "In7.Cu" signal "GND3")
		(18 "In8.Cu" signal "VCC")
		(20 "In9.Cu" signal "VCC1")
		(22 "In10.Cu" signal "GND4")
		(24 "In11.Cu" signal "IN4")
		(26 "In12.Cu" signal "GND5")
		(28 "In13.Cu" signal "IN5")
		(30 "In14.Cu" signal "GND6")
		(32 "In15.Cu" signal "IN6")
		(34 "In16.Cu" signal "GND7")
		(2 "B.Cu" signal "BOTTOM")
		(9 "F.Adhes" user "F.Adhesive")
		(11 "B.Adhes" user "B.Adhesive")
		(13 "F.Paste" user "Package Geometry/Pastemask Top")
		(15 "B.Paste" user "Package Geometry/Pastemask Bottom")
		(5 "F.SilkS" user "Ref Des/Silkscreen Top")
		(7 "B.SilkS" user "Ref Des/Silkscreen Bottom")
		(1 "F.Mask" user "Board Geometry/Soldermask Top")
		(3 "B.Mask" user "Board Geometry/Soldermask Bottom")
		(17 "Dwgs.User" user "User.Drawings")
		(19 "Cmts.User" user "User.Comments")
		(21 "Eco1.User" user "User.Eco1")
		(23 "Eco2.User" user "User.Eco2")
		(25 "Edge.Cuts" user "Board Geometry/Outline")
		(27 "Margin" user)
		(31 "F.CrtYd" user "Package Geometry/Place Bound Top")
		(29 "B.CrtYd" user "Package Geometry/Place Bound Bottom")
		(35 "F.Fab" user "Ref Des/Assembly Top")
		(33 "B.Fab" user "Ref Des/Assembly Bottom")
	)
	(footprint ""
		(layer "B.Cu")
		(at 115.70589 -258.795266 180)
		(property "Reference" "C2441"
			(at 0 0 0)
			(layer "B.SilkS")
			(hide yes)
			(effects
				(font
					(size 1.27 1.27)
				)
				(justify mirror)
			)
		)
		(property "Value" ""
			(at 0 0 0)
			(layer "B.Fab")
			(effects
				(font
					(size 1.27 1.27)
				)
				(justify mirror)
			)
		)
		(duplicate_pad_numbers_are_jumpers no)
		(fp_line
			(start 0.7874 0.4064)
			(end 0.7874 -0.4064)
			(stroke
				(width 0.1524)
				(type default)
			)
			(layer "B.SilkS")
		)
		(fp_line
			(start 0.7874 -0.4064)
			(end -0.7874 -0.4064)
			(stroke
				(width 0.1524)
				(type default)
			)
			(layer "B.SilkS")
		)
		(fp_line
			(start -0.7874 0.4064)
			(end 0.7874 0.4064)
			(stroke
				(width 0.1524)
				(type default)
			)
			(layer "B.SilkS")
		)
		(fp_line
			(start -0.7874 -0.4064)
			(end -0.7874 0.4064)
			(stroke
				(width 0.1524)
				(type default)
			)
			(layer "B.SilkS")
		)
		(fp_line
			(start 0.67945 0.3048)
			(end 0.67945 -0.305054)
			(stroke
				(width 0.1)
				(type default)
			)
			(layer "B.Fab")
		)
		(fp_line
			(start 0.67945 -0.305054)
			(end 0.12065 -0.305054)
			(stroke
				(width 0.1)
				(type default)
			)
			(layer "B.Fab")
		)
		(fp_line
			(start 0.12065 0.3048)
			(end 0.67945 0.3048)
			(stroke
				(width 0.1)
				(type default)
			)
			(layer "B.Fab")
		)
		(fp_line
			(start 0.12065 0.2794)
			(end 0.12065 0.3048)
			(stroke
				(width 0.1)
				(type default)
			)
			(layer "B.Fab")
		)
		(fp_line
			(start 0.12065 -0.2794)
			(end -0.12065 -0.2794)
			(stroke
				(width 0.1)
				(type default)
			)
			(layer "B.Fab")
		)
		(fp_line
			(start 0.12065 -0.305054)
			(end 0.12065 -0.2794)
			(stroke
				(width 0.1)
				(type default)
			)
			(layer "B.Fab")
		)
		(fp_line
			(start -0.120396 0.3048)
			(end -0.120396 0.2794)
			(stroke
				(width 0.1)
				(type default)
			)
			(layer "B.Fab")
		)
		(fp_line
			(start -0.120396 0.2794)
			(end 0.12065 0.2794)
			(stroke
				(width 0.1)
				(type default)
			)
			(layer "B.Fab")
		)
		(fp_line
			(start -0.12065 -0.2794)
			(end -0.12065 -0.3048)
			(stroke
				(width 0.1)
				(type default)
			)
			(layer "B.Fab")
		)
		(fp_line
			(start -0.12065 -0.3048)
			(end -0.67945 -0.3048)
			(stroke
				(width 0.1)
				(type default)
			)
			(layer "B.Fab")
		)
		(fp_line
			(start -0.67945 0.3048)
			(end -0.120396 0.3048)
			(stroke
				(width 0.1)
				(type default)
			)
			(layer "B.Fab")
		)
		(fp_line
			(start -0.67945 -0.3048)
			(end -0.67945 0.3048)
			(stroke
				(width 0.1)
				(type default)
			)
			(layer "B.Fab")
		)
		(pad "1" smd circle
			(at 0.40005 0)
			(size 0 0)
			(layers "B.Cu" "B.Mask" "B.Paste")
			(net "PVDDCR_SOC_P1")
		)
		(pad "2" smd circle
			(at -0.40005 0)
			(size 0 0)
			(layers "B.Cu" "B.Mask" "B.Paste")
			(net "GND")
		)
	)
	(footprint ""
		(layer "B.Cu")
		(at 187.96 -418.846 90)
		(property "Reference" "U8005"
			(at -2.277364 2.563622 270)
			(unlocked yes)
			(layer "B.SilkS")
			(effects
				(font
					(size 0.7874 0.5842)
					(thickness 0.1524)
				)
				(justify left mirror)
			)
		)
		(property "Value" ""
			(at 0 0 90)
			(layer "B.Fab")
			(effects
				(font
					(size 1.27 1.27)
				)
				(justify mirror)
			)
		)
		(duplicate_pad_numbers_are_jumpers no)
		(fp_line
			(start 1.868424 -1.519936)
			(end 1.868424 1.519936)
			(stroke
				(width 0.1524)
				(type default)
			)
			(layer "B.SilkS")
		)
		(fp_line
			(start -1.868424 -1.519936)
			(end 1.868424 -1.519936)
			(stroke
				(width 0.1524)
				(type default)
			)
			(layer "B.SilkS")
		)
		(fp_line
			(start 1.868424 1.519936)
			(end -1.868424 1.519936)
			(stroke
				(width 0.1524)
				(type default)
			)
			(layer "B.SilkS")
		)
		(fp_line
			(start -1.868424 1.519936)
			(end -1.868424 -1.519936)
			(stroke
				(width 0.1524)
				(type default)
			)
			(layer "B.SilkS")
		)
		(fp_line
			(start 0.700024 -1.519936)
			(end 0.700024 1.519936)
			(stroke
				(width 0.1)
				(type default)
			)
			(layer "B.Fab")
		)
		(fp_line
			(start -0.700024 -1.519936)
			(end 0.700024 -1.519936)
			(stroke
				(width 0.1)
				(type default)
			)
			(layer "B.Fab")
		)
		(fp_line
			(start 0.700024 1.519936)
			(end -0.700024 1.519936)
			(stroke
				(width 0.1)
				(type default)
			)
			(layer "B.Fab")
		)
		(fp_line
			(start -0.700024 1.519936)
			(end -0.700024 -1.519936)
			(stroke
				(width 0.1)
				(type default)
			)
			(layer "B.Fab")
		)
		(pad "1" smd rect
			(at 1.18491 -0.94996)
			(size 0.6096 1.0668)
			(layers "B.Cu" "B.Mask" "B.Paste")
			(net "OC_P2V5_COMP")
		)
		(pad "2" smd rect
			(at 1.18491 0.94996)
			(size 0.6096 1.0668)
			(layers "B.Cu" "B.Mask" "B.Paste")
			(net "GND")
		)
		(pad "3" smd rect
			(at -1.18491 0)
			(size 0.6096 1.0668)
			(layers "B.Cu" "B.Mask" "B.Paste")
			(net "Net_10848")
		)
	)
	(footprint ""
		(layer "B.Cu")
		(at 121.8184 -388.011162 -90)
		(property "Reference" "C440"
			(at 0 0 90)
			(layer "B.SilkS")
			(hide yes)
			(effects
				(font
					(size 1.27 1.27)
				)
				(justify mirror)
			)
		)
		(property "Value" ""
			(at 0 0 90)
			(layer "B.Fab")
			(effects
				(font
					(size 1.27 1.27)
				)
				(justify mirror)
			)
		)
		(duplicate_pad_numbers_are_jumpers no)
		(fp_line
			(start -0.299974 0.150114)
			(end 0.299974 0.150114)
			(stroke
				(width 0.1)
				(type default)
			)
			(layer "B.Fab")
		)
		(fp_line
			(start 0.299974 0.150114)
			(end 0.299974 -0.150114)
			(stroke
				(width 0.1)
				(type default)
			)
			(layer "B.Fab")
		)
		(fp_line
			(start -0.299974 -0.150114)
			(end -0.299974 0.150114)
			(stroke
				(width 0.1)
				(type default)
			)
			(layer "B.Fab")
		)
		(fp_line
			(start 0.299974 -0.150114)
			(end -0.299974 -0.150114)
			(stroke
				(width 0.1)
				(type default)
			)
			(layer "B.Fab")
		)
		(pad "1" smd rect
			(at 0.2667 0 90)
			(size 0.3048 0.381)
			(layers "B.Cu" "B.Mask" "B.Paste")
			(net "P1V8_CPU1_RT3_1A")
		)
		(pad "2" smd rect
			(at -0.2667 0 90)
			(size 0.3048 0.381)
			(layers "B.Cu" "B.Mask" "B.Paste")
			(net "GND")
		)
	)
)
